(kicad_pcb
	(version 20260206)
	(generator "pcbnew")
	(generator_version "10.0")
	(general
		(thickness 1.6)
		(legacy_teardrops no)
	)
	(paper "A4")
	(title_block
		(title "04192023_DAF0TMB3IC0_F0TG_MB_C_brd_V02_OCP.brd")
		(comment 1 "Grand Teton / footprints 1031-1037 of 8354")
	)
	(layers
		(0 "F.Cu" signal "TOP")
		(4 "In1.Cu" signal "GND")
		(6 "In2.Cu" signal "IN1")
		(8 "In3.Cu" signal "GND1")
		(10 "In4.Cu" signal "IN2")
		(12 "In5.Cu" signal "GND2")
		(14 "In6.Cu" signal "IN3")
		(16 "In7.Cu" signal "GND3")
		(18 "In8.Cu" signal "VCC")
		(20 "In9.Cu" signal "VCC1")
		(22 "In10.Cu" signal "GND4")
		(24 "In11.Cu" signal "IN4")
		(26 "In12.Cu" signal "GND5")
		(28 "In13.Cu" signal "IN5")
		(30 "In14.Cu" signal "GND6")
		(32 "In15.Cu" signal "IN6")
		(34 "In16.Cu" signal "GND7")
		(2 "B.Cu" signal "BOTTOM")
		(9 "F.Adhes" user "F.Adhesive")
		(11 "B.Adhes" user "B.Adhesive")
		(13 "F.Paste" user "Package Geometry/Pastemask Top")
		(15 "B.Paste" user "Package Geometry/Pastemask Bottom")
		(5 "F.SilkS" user "Ref Des/Silkscreen Top")
		(7 "B.SilkS" user "Ref Des/Silkscreen Bottom")
		(1 "F.Mask" user "Board Geometry/Soldermask Top")
		(3 "B.Mask" user "Board Geometry/Soldermask Bottom")
		(17 "Dwgs.User" user "User.Drawings")
		(19 "Cmts.User" user "User.Comments")
		(21 "Eco1.User" user "User.Eco1")
		(23 "Eco2.User" user "User.Eco2")
		(25 "Edge.Cuts" user "Board Geometry/Outline")
		(27 "Margin" user)
		(31 "F.CrtYd" user "Package Geometry/Place Bound Top")
		(29 "B.CrtYd" user "Package Geometry/Place Bound Bottom")
		(35 "F.Fab" user "Ref Des/Assembly Top")
		(33 "B.Fab" user "Ref Des/Assembly Bottom")
	)
	(footprint ""
		(layer "F.Cu")
		(at 310.75757 -22.185884 90)
		(property "Reference" "C63"
			(at 0 0 90)
			(layer "F.SilkS")
			(hide yes)
			(effects
				(font
					(size 1.27 1.27)
				)
			)
		)
		(property "Value" ""
			(at 0 0 90)
			(layer "F.Fab")
			(effects
				(font
					(size 1.27 1.27)
				)
			)
		)
		(duplicate_pad_numbers_are_jumpers no)
		(fp_line
			(start 0.7874 -0.4064)
			(end 0.7874 0.4064)
			(stroke
				(width 0.1524)
				(type default)
			)
			(layer "F.SilkS")
		)
		(fp_line
			(start -0.7874 -0.4064)
			(end 0.7874 -0.4064)
			(stroke
				(width 0.1524)
				(type default)
			)
			(layer "F.SilkS")
		)
		(fp_line
			(start 0.7874 0.4064)
			(end -0.7874 0.4064)
			(stroke
				(width 0.1524)
				(type default)
			)
			(layer "F.SilkS")
		)
		(fp_line
			(start -0.7874 0.4064)
			(end -0.7874 -0.4064)
			(stroke
				(width 0.1524)
				(type default)
			)
			(layer "F.SilkS")
		)
		(fp_line
			(start -0.12065 -0.305054)
			(end -0.12065 -0.2794)
			(stroke
				(width 0.1)
				(type default)
			)
			(layer "F.Fab")
		)
		(fp_line
			(start -0.67945 -0.305054)
			(end -0.12065 -0.305054)
			(stroke
				(width 0.1)
				(type default)
			)
			(layer "F.Fab")
		)
		(fp_line
			(start 0.67945 -0.3048)
			(end 0.67945 0.3048)
			(stroke
				(width 0.1)
				(type default)
			)
			(layer "F.Fab")
		)
		(fp_line
			(start 0.12065 -0.3048)
			(end 0.67945 -0.3048)
			(stroke
				(width 0.1)
				(type default)
			)
			(layer "F.Fab")
		)
		(fp_line
			(start 0.12065 -0.2794)
			(end 0.12065 -0.3048)
			(stroke
				(width 0.1)
				(type default)
			)
			(layer "F.Fab")
		)
		(fp_line
			(start -0.12065 -0.2794)
			(end 0.12065 -0.2794)
			(stroke
				(width 0.1)
				(type default)
			)
			(layer "F.Fab")
		)
		(fp_line
			(start 0.120396 0.2794)
			(end -0.12065 0.2794)
			(stroke
				(width 0.1)
				(type default)
			)
			(layer "F.Fab")
		)
		(fp_line
			(start -0.12065 0.2794)
			(end -0.12065 0.3048)
			(stroke
				(width 0.1)
				(type default)
			)
			(layer "F.Fab")
		)
		(fp_line
			(start 0.67945 0.3048)
			(end 0.120396 0.3048)
			(stroke
				(width 0.1)
				(type default)
			)
			(layer "F.Fab")
		)
		(fp_line
			(start 0.120396 0.3048)
			(end 0.120396 0.2794)
			(stroke
				(width 0.1)
				(type default)
			)
			(layer "F.Fab")
		)
		(fp_line
			(start -0.12065 0.3048)
			(end -0.67945 0.3048)
			(stroke
				(width 0.1)
				(type default)
			)
			(layer "F.Fab")
		)
		(fp_line
			(start -0.67945 0.3048)
			(end -0.67945 -0.305054)
			(stroke
				(width 0.1)
				(type default)
			)
			(layer "F.Fab")
		)
		(pad "1" smd circle
			(at -0.40005 0 90)
			(size 0 0)
			(layers "F.Cu" "F.Mask" "F.Paste")
			(net "UART_CPU0_SCM_LVC3_UART1_R_RX")
		)
		(pad "2" smd circle
			(at 0.40005 0 90)
			(size 0 0)
			(layers "F.Cu" "F.Mask" "F.Paste")
			(net "GND")
		)
	)
	(footprint ""
		(layer "F.Cu")
		(at 76.431902 -373.03583 -90)
		(property "Reference" "C736"
			(at 0 0 270)
			(layer "F.SilkS")
			(hide yes)
			(effects
				(font
					(size 1.27 1.27)
				)
			)
		)
		(property "Value" ""
			(at 0 0 270)
			(layer "F.Fab")
			(effects
				(font
					(size 1.27 1.27)
				)
			)
		)
		(duplicate_pad_numbers_are_jumpers no)
		(fp_line
			(start -0.299974 0.150114)
			(end -0.299974 -0.150114)
			(stroke
				(width 0.1)
				(type default)
			)
			(layer "F.Fab")
		)
		(fp_line
			(start 0.299974 0.150114)
			(end -0.299974 0.150114)
			(stroke
				(width 0.1)
				(type default)
			)
			(layer "F.Fab")
		)
		(fp_line
			(start -0.299974 -0.150114)
			(end 0.299974 -0.150114)
			(stroke
				(width 0.1)
				(type default)
			)
			(layer "F.Fab")
		)
		(fp_line
			(start 0.299974 -0.150114)
			(end 0.299974 0.150114)
			(stroke
				(width 0.1)
				(type default)
			)
			(layer "F.Fab")
		)
		(pad "1" smd rect
			(at -0.2667 0 270)
			(size 0.3048 0.381)
			(layers "F.Cu" "F.Mask" "F.Paste")
			(net "P5E_CPU1_P1_TX_C_DN<2>")
		)
		(pad "2" smd rect
			(at 0.2667 0 270)
			(size 0.3048 0.381)
			(layers "F.Cu" "F.Mask" "F.Paste")
			(net "P5E_CPU1_P1_TX_DN<2>")
		)
	)
	(footprint ""
		(layer "F.Cu")
		(at 48.11014 -99.60864 -90)
		(property "Reference" "R954"
			(at 0 0 270)
			(layer "F.SilkS")
			(hide yes)
			(effects
				(font
					(size 1.27 1.27)
				)
			)
		)
		(property "Value" ""
			(at 0 0 270)
			(layer "F.Fab")
			(effects
				(font
					(size 1.27 1.27)
				)
			)
		)
		(duplicate_pad_numbers_are_jumpers no)
		(fp_line
			(start -0.7874 0.4064)
			(end -0.7874 -0.4064)
			(stroke
				(width 0.1524)
				(type default)
			)
			(layer "F.SilkS")
		)
		(fp_line
			(start 0.7874 0.4064)
			(end -0.7874 0.4064)
			(stroke
				(width 0.1524)
				(type default)
			)
			(layer "F.SilkS")
		)
		(fp_line
			(start -0.7874 -0.4064)
			(end 0.7874 -0.4064)
			(stroke
				(width 0.1524)
				(type default)
			)
			(layer "F.SilkS")
		)
		(fp_line
			(start 0.7874 -0.4064)
			(end 0.7874 0.4064)
			(stroke
				(width 0.1524)
				(type default)
			)
			(layer "F.SilkS")
		)
		(fp_line
			(start -0.67945 0.3048)
			(end -0.67945 -0.305054)
			(stroke
				(width 0.1)
				(type default)
			)
			(layer "F.Fab")
		)
		(fp_line
			(start -0.12065 0.3048)
			(end -0.67945 0.3048)
			(stroke
				(width 0.1)
				(type default)
			)
			(layer "F.Fab")
		)
		(fp_line
			(start 0.120396 0.3048)
			(end 0.120396 0.2794)
			(stroke
				(width 0.1)
				(type default)
			)
			(layer "F.Fab")
		)
		(fp_line
			(start 0.67945 0.3048)
			(end 0.120396 0.3048)
			(stroke
				(width 0.1)
				(type default)
			)
			(layer "F.Fab")
		)
		(fp_line
			(start -0.12065 0.2794)
			(end -0.12065 0.3048)
			(stroke
				(width 0.1)
				(type default)
			)
			(layer "F.Fab")
		)
		(fp_line
			(start 0.120396 0.2794)
			(end -0.12065 0.2794)
			(stroke
				(width 0.1)
				(type default)
			)
			(layer "F.Fab")
		)
		(fp_line
			(start -0.12065 -0.2794)
			(end 0.12065 -0.2794)
			(stroke
				(width 0.1)
				(type default)
			)
			(layer "F.Fab")
		)
		(fp_line
			(start 0.12065 -0.2794)
			(end 0.12065 -0.3048)
			(stroke
				(width 0.1)
				(type default)
			)
			(layer "F.Fab")
		)
		(fp_line
			(start 0.12065 -0.3048)
			(end 0.67945 -0.3048)
			(stroke
				(width 0.1)
				(type default)
			)
			(layer "F.Fab")
		)
		(fp_line
			(start 0.67945 -0.3048)
			(end 0.67945 0.3048)
			(stroke
				(width 0.1)
				(type default)
			)
			(layer "F.Fab")
		)
		(fp_line
			(start -0.67945 -0.305054)
			(end -0.12065 -0.305054)
			(stroke
				(width 0.1)
				(type default)
			)
			(layer "F.Fab")
		)
		(fp_line
			(start -0.12065 -0.305054)
			(end -0.12065 -0.2794)
			(stroke
				(width 0.1)
				(type default)
			)
			(layer "F.Fab")
		)
		(pad "1" smd circle
			(at -0.40005 0 270)
			(size 0 0)
			(layers "F.Cu" "F.Mask" "F.Paste")
			(net "P3V3_AUX_DSC_VOL")
		)
		(pad "2" smd circle
			(at 0.40005 0 270)
			(size 0 0)
			(layers "F.Cu" "F.Mask" "F.Paste")
			(net "GND")
		)
	)
	(footprint ""
		(layer "F.Cu")
		(at 128.768856 -156.443934 90)
		(property "Reference" "PC349_3"
			(at 0 0 90)
			(layer "F.SilkS")
			(hide yes)
			(effects
				(font
					(size 1.27 1.27)
				)
			)
		)
		(property "Value" ""
			(at 0 0 90)
			(layer "F.Fab")
			(effects
				(font
					(size 1.27 1.27)
				)
			)
		)
		(duplicate_pad_numbers_are_jumpers no)
		(fp_line
			(start 0.7874 -0.4064)
			(end 0.7874 0.4064)
			(stroke
				(width 0.1524)
				(type default)
			)
			(layer "F.SilkS")
		)
		(fp_line
			(start -0.7874 -0.4064)
			(end 0.7874 -0.4064)
			(stroke
				(width 0.1524)
				(type default)
			)
			(layer "F.SilkS")
		)
		(fp_line
			(start 0.7874 0.4064)
			(end -0.7874 0.4064)
			(stroke
				(width 0.1524)
				(type default)
			)
			(layer "F.SilkS")
		)
		(fp_line
			(start -0.7874 0.4064)
			(end -0.7874 -0.4064)
			(stroke
				(width 0.1524)
				(type default)
			)
			(layer "F.SilkS")
		)
		(fp_line
			(start -0.12065 -0.305054)
			(end -0.12065 -0.2794)
			(stroke
				(width 0.1)
				(type default)
			)
			(layer "F.Fab")
		)
		(fp_line
			(start -0.67945 -0.305054)
			(end -0.12065 -0.305054)
			(stroke
				(width 0.1)
				(type default)
			)
			(layer "F.Fab")
		)
		(fp_line
			(start 0.67945 -0.3048)
			(end 0.67945 0.3048)
			(stroke
				(width 0.1)
				(type default)
			)
			(layer "F.Fab")
		)
		(fp_line
			(start 0.12065 -0.3048)
			(end 0.67945 -0.3048)
			(stroke
				(width 0.1)
				(type default)
			)
			(layer "F.Fab")
		)
		(fp_line
			(start 0.12065 -0.2794)
			(end 0.12065 -0.3048)
			(stroke
				(width 0.1)
				(type default)
			)
			(layer "F.Fab")
		)
		(fp_line
			(start -0.12065 -0.2794)
			(end 0.12065 -0.2794)
			(stroke
				(width 0.1)
				(type default)
			)
			(layer "F.Fab")
		)
		(fp_line
			(start 0.120396 0.2794)
			(end -0.12065 0.2794)
			(stroke
				(width 0.1)
				(type default)
			)
			(layer "F.Fab")
		)
		(fp_line
			(start -0.12065 0.2794)
			(end -0.12065 0.3048)
			(stroke
				(width 0.1)
				(type default)
			)
			(layer "F.Fab")
		)
		(fp_line
			(start 0.67945 0.3048)
			(end 0.120396 0.3048)
			(stroke
				(width 0.1)
				(type default)
			)
			(layer "F.Fab")
		)
		(fp_line
			(start 0.120396 0.3048)
			(end 0.120396 0.2794)
			(stroke
				(width 0.1)
				(type default)
			)
			(layer "F.Fab")
		)
		(fp_line
			(start -0.12065 0.3048)
			(end -0.67945 0.3048)
			(stroke
				(width 0.1)
				(type default)
			)
			(layer "F.Fab")
		)
		(fp_line
			(start -0.67945 0.3048)
			(end -0.67945 -0.305054)
			(stroke
				(width 0.1)
				(type default)
			)
			(layer "F.Fab")
		)
		(pad "1" smd circle
			(at -0.40005 0 90)
			(size 0 0)
			(layers "F.Cu" "F.Mask" "F.Paste")
			(net "SW_P12V_AUX_PVDDCR_SOC_P1_FLT")
		)
		(pad "2" smd circle
			(at 0.40005 0 90)
			(size 0 0)
			(layers "F.Cu" "F.Mask" "F.Paste")
			(net "GND")
		)
	)
	(footprint ""
		(layer "F.Cu")
		(at 457.200508 -72.373236 180)
		(property "Reference" "PC1866"
			(at -2.201164 -2.058162 0)
			(unlocked yes)
			(layer "F.SilkS")
			(effects
				(font
					(size 0.7874 0.5842)
					(thickness 0.1524)
				)
				(justify left)
			)
		)
		(property "Value" ""
			(at 0 0 180)
			(layer "F.Fab")
			(effects
				(font
					(size 1.27 1.27)
				)
			)
		)
		(duplicate_pad_numbers_are_jumpers no)
		(fp_line
			(start -3.400044 1.249934)
			(end 3.400044 1.249934)
			(stroke
				(width 0.1524)
				(type default)
			)
			(layer "F.SilkS")
		)
		(fp_circle
			(center 0 1.249934)
			(end -3.400044 1.249934)
			(stroke
				(width 0.1524)
				(type default)
			)
			(fill no)
			(layer "F.SilkS")
		)
		(fp_poly
			(pts
				(arc
					(start 3.400044 1.249934)
					(mid 0 4.649978)
					(end -3.400044 1.249934)
				)
			)
			(stroke
				(width 0)
				(type default)
			)
			(fill yes)
			(layer "F.SilkS")
		)
		(fp_circle
			(center 0 1.249934)
			(end -3.400044 1.249934)
			(stroke
				(width 0.1)
				(type default)
			)
			(fill no)
			(layer "F.Fab")
		)
		(pad "1" thru_hole rect
			(at 0 0 180)
			(size 1.524 1.524)
			(drill 1.016)
			(layers "*.Cu" "*.Mask")
			(remove_unused_layers no)
			(net "P3V3_AUX")
			(clearance 0)
			(padstack
				(mode front_inner_back)
				(layer "Inner"
					(shape circle)
					(size 1.524 1.524)
					(clearance 0)
				)
				(layer "B.Cu"
					(shape rect)
					(size 1.524 1.524)
					(clearance 0)
				)
			)
		)
		(pad "2" thru_hole circle
			(at 0 2.500122 180)
			(size 1.524 1.524)
			(drill 1.016)
			(layers "*.Cu" "*.Mask")
			(remove_unused_layers no)
			(net "GND")
			(clearance 0)
		)
	)
	(footprint ""
		(layer "F.Cu")
		(at 319.137538 -117.950488)
		(property "Reference" "R710"
			(at 0 0 0)
			(layer "F.SilkS")
			(hide yes)
			(effects
				(font
					(size 1.27 1.27)
				)
			)
		)
		(property "Value" ""
			(at 0 0 0)
			(layer "F.Fab")
			(effects
				(font
					(size 1.27 1.27)
				)
			)
		)
		(duplicate_pad_numbers_are_jumpers no)
		(fp_line
			(start -0.7874 -0.4064)
			(end 0.7874 -0.4064)
			(stroke
				(width 0.1524)
				(type default)
			)
			(layer "F.SilkS")
		)
		(fp_line
			(start -0.7874 0.4064)
			(end -0.7874 -0.4064)
			(stroke
				(width 0.1524)
				(type default)
			)
			(layer "F.SilkS")
		)
		(fp_line
			(start 0.7874 -0.4064)
			(end 0.7874 0.4064)
			(stroke
				(width 0.1524)
				(type default)
			)
			(layer "F.SilkS")
		)
		(fp_line
			(start 0.7874 0.4064)
			(end -0.7874 0.4064)
			(stroke
				(width 0.1524)
				(type default)
			)
			(layer "F.SilkS")
		)
		(fp_line
			(start -0.67945 -0.305054)
			(end -0.12065 -0.305054)
			(stroke
				(width 0.1)
				(type default)
			)
			(layer "F.Fab")
		)
		(fp_line
			(start -0.67945 0.3048)
			(end -0.67945 -0.305054)
			(stroke
				(width 0.1)
				(type default)
			)
			(layer "F.Fab")
		)
		(fp_line
			(start -0.12065 -0.305054)
			(end -0.12065 -0.2794)
			(stroke
				(width 0.1)
				(type default)
			)
			(layer "F.Fab")
		)
		(fp_line
			(start -0.12065 -0.2794)
			(end 0.12065 -0.2794)
			(stroke
				(width 0.1)
				(type default)
			)
			(layer "F.Fab")
		)
		(fp_line
			(start -0.12065 0.2794)
			(end -0.12065 0.3048)
			(stroke
				(width 0.1)
				(type default)
			)
			(layer "F.Fab")
		)
		(fp_line
			(start -0.12065 0.3048)
			(end -0.67945 0.3048)
			(stroke
				(width 0.1)
				(type default)
			)
			(layer "F.Fab")
		)
		(fp_line
			(start 0.120396 0.2794)
			(end -0.12065 0.2794)
			(stroke
				(width 0.1)
				(type default)
			)
			(layer "F.Fab")
		)
		(fp_line
			(start 0.120396 0.3048)
			(end 0.120396 0.2794)
			(stroke
				(width 0.1)
				(type default)
			)
			(layer "F.Fab")
		)
		(fp_line
			(start 0.12065 -0.3048)
			(end 0.67945 -0.3048)
			(stroke
				(width 0.1)
				(type default)
			)
			(layer "F.Fab")
		)
		(fp_line
			(start 0.12065 -0.2794)
			(end 0.12065 -0.3048)
			(stroke
				(width 0.1)
				(type default)
			)
			(layer "F.Fab")
		)
		(fp_line
			(start 0.67945 -0.3048)
			(end 0.67945 0.3048)
			(stroke
				(width 0.1)
				(type default)
			)
			(layer "F.Fab")
		)
		(fp_line
			(start 0.67945 0.3048)
			(end 0.120396 0.3048)
			(stroke
				(width 0.1)
				(type default)
			)
			(layer "F.Fab")
		)
		(pad "1" smd circle
			(at -0.40005 0)
			(size 0 0)
			(layers "F.Cu" "F.Mask" "F.Paste")
			(net "PD_MB_FRU_WP")
		)
		(pad "2" smd circle
			(at 0.40005 0)
			(size 0 0)
			(layers "F.Cu" "F.Mask" "F.Paste")
			(net "GND")
		)
	)
	(footprint ""
		(layer "F.Cu")
		(at 157.353 -111.887 90)
		(property "Reference" "R1128"
			(at 0 0 90)
			(layer "F.SilkS")
			(hide yes)
			(effects
				(font
					(size 1.27 1.27)
				)
			)
		)
		(property "Value" ""
			(at 0 0 90)
			(layer "F.Fab")
			(effects
				(font
					(size 1.27 1.27)
				)
			)
		)
		(duplicate_pad_numbers_are_jumpers no)
		(fp_line
			(start 0.7874 -0.4064)
			(end 0.7874 0.4064)
			(stroke
				(width 0.1524)
				(type default)
			)
			(layer "F.SilkS")
		)
		(fp_line
			(start -0.7874 -0.4064)
			(end 0.7874 -0.4064)
			(stroke
				(width 0.1524)
				(type default)
			)
			(layer "F.SilkS")
		)
		(fp_line
			(start 0.7874 0.4064)
			(end -0.7874 0.4064)
			(stroke
				(width 0.1524)
				(type default)
			)
			(layer "F.SilkS")
		)
		(fp_line
			(start -0.7874 0.4064)
			(end -0.7874 -0.4064)
			(stroke
				(width 0.1524)
				(type default)
			)
			(layer "F.SilkS")
		)
		(fp_line
			(start -0.12065 -0.305054)
			(end -0.12065 -0.2794)
			(stroke
				(width 0.1)
				(type default)
			)
			(layer "F.Fab")
		)
		(fp_line
			(start -0.67945 -0.305054)
			(end -0.12065 -0.305054)
			(stroke
				(width 0.1)
				(type default)
			)
			(layer "F.Fab")
		)
		(fp_line
			(start 0.67945 -0.3048)
			(end 0.67945 0.3048)
			(stroke
				(width 0.1)
				(type default)
			)
			(layer "F.Fab")
		)
		(fp_line
			(start 0.12065 -0.3048)
			(end 0.67945 -0.3048)
			(stroke
				(width 0.1)
				(type default)
			)
			(layer "F.Fab")
		)
		(fp_line
			(start 0.12065 -0.2794)
			(end 0.12065 -0.3048)
			(stroke
				(width 0.1)
				(type default)
			)
			(layer "F.Fab")
		)
		(fp_line
			(start -0.12065 -0.2794)
			(end 0.12065 -0.2794)
			(stroke
				(width 0.1)
				(type default)
			)
			(layer "F.Fab")
		)
		(fp_line
			(start 0.120396 0.2794)
			(end -0.12065 0.2794)
			(stroke
				(width 0.1)
				(type default)
			)
			(layer "F.Fab")
		)
		(fp_line
			(start -0.12065 0.2794)
			(end -0.12065 0.3048)
			(stroke
				(width 0.1)
				(type default)
			)
			(layer "F.Fab")
		)
		(fp_line
			(start 0.67945 0.3048)
			(end 0.120396 0.3048)
			(stroke
				(width 0.1)
				(type default)
			)
			(layer "F.Fab")
		)
		(fp_line
			(start 0.120396 0.3048)
			(end 0.120396 0.2794)
			(stroke
				(width 0.1)
				(type default)
			)
			(layer "F.Fab")
		)
		(fp_line
			(start -0.12065 0.3048)
			(end -0.67945 0.3048)
			(stroke
				(width 0.1)
				(type default)
			)
			(layer "F.Fab")
		)
		(fp_line
			(start -0.67945 0.3048)
			(end -0.67945 -0.305054)
			(stroke
				(width 0.1)
				(type default)
			)
			(layer "F.Fab")
		)
		(pad "1" smd circle
			(at -0.40005 0 90)
			(size 0 0)
			(layers "F.Cu" "F.Mask" "F.Paste")
			(net "P3V3_AUX")
		)
		(pad "2" smd circle
			(at 0.40005 0 90)
			(size 0 0)
			(layers "F.Cu" "F.Mask" "F.Paste")
			(net "HP_LVC3_OCP_SFF_PRSNT2")
		)
	)
)
